FILE_TYPE = CONNECTIVITY;
{Allegro Design Entry HDL 17.2-2016 S081 (4005846) 1/11/2022}
"PAGE_NUMBER" = 158;
0"NC";
END.
